# T6G (Grand Teton) — schematic netlist excerpt (pin names and nets, part order shuffled) for the footprints in the layout excerpt that follows; sources: Cadence DE-HDL packaged netlist, KiCad conversion of 04192023_DAF0TMB3IC0_F0TG_MB_C_brd_V02_OCP.brd

R2907  Q_RES  5.11K 1% CHIP  pkg 0402LF  page 257 : A = P3V3_AUX ; B = P3V3_AUX_ADC
R1346  Q_RES  33.2 1% CHIP  pkg 0402LF  page 251 : A = SMB_INA230_3V3AUX_SCL ; B = SMB_INA230_7_3V3AUX_SCL_R

(kicad_pcb
	(version 20260206)
	(generator "pcbnew")
	(generator_version "10.0")
	(general
		(thickness 1.6)
		(legacy_teardrops no)
	)
	(paper "A4")
	(title_block
		(title "04192023_DAF0TMB3IC0_F0TG_MB_C_brd_V02_OCP.brd")
		(comment 1 "Grand Teton / footprints 704-705 of 8354")
	)
	(layers
		(0 "F.Cu" signal "TOP")
		(4 "In1.Cu" signal "GND")
		(6 "In2.Cu" signal "IN1")
		(8 "In3.Cu" signal "GND1")
		(10 "In4.Cu" signal "IN2")
		(12 "In5.Cu" signal "GND2")
		(14 "In6.Cu" signal "IN3")
		(16 "In7.Cu" signal "GND3")
		(18 "In8.Cu" signal "VCC")
		(20 "In9.Cu" signal "VCC1")
		(22 "In10.Cu" signal "GND4")
		(24 "In11.Cu" signal "IN4")
		(26 "In12.Cu" signal "GND5")
		(28 "In13.Cu" signal "IN5")
		(30 "In14.Cu" signal "GND6")
		(32 "In15.Cu" signal "IN6")
		(34 "In16.Cu" signal "GND7")
		(2 "B.Cu" signal "BOTTOM")
		(9 "F.Adhes" user "F.Adhesive")
		(11 "B.Adhes" user "B.Adhesive")
		(13 "F.Paste" user "Package Geometry/Pastemask Top")
		(15 "B.Paste" user "Package Geometry/Pastemask Bottom")
		(5 "F.SilkS" user "Ref Des/Silkscreen Top")
		(7 "B.SilkS" user "Ref Des/Silkscreen Bottom")
		(1 "F.Mask" user "Board Geometry/Soldermask Top")
		(3 "B.Mask" user "Board Geometry/Soldermask Bottom")
		(17 "Dwgs.User" user "User.Drawings")
		(19 "Cmts.User" user "User.Comments")
		(21 "Eco1.User" user "User.Eco1")
		(23 "Eco2.User" user "User.Eco2")
		(25 "Edge.Cuts" user "Board Geometry/Outline")
		(27 "Margin" user)
		(31 "F.CrtYd" user "Package Geometry/Place Bound Top")
		(29 "B.CrtYd" user "Package Geometry/Place Bound Bottom")
		(35 "F.Fab" user "Ref Des/Assembly Top")
		(33 "B.Fab" user "Ref Des/Assembly Bottom")
	)
	(footprint ""
		(layer "F.Cu")
		(at 146.567398 -49.153064)
		(property "Reference" "R1346"
			(at 0 0 0)
			(layer "F.SilkS")
			(hide yes)
			(effects
				(font
					(size 1.27 1.27)
				)
			)
		)
		(property "Value" ""
			(at 0 0 0)
			(layer "F.Fab")
			(effects
				(font
					(size 1.27 1.27)
				)
			)
		)
		(duplicate_pad_numbers_are_jumpers no)
		(fp_line
			(start -0.7874 -0.4064)
			(end 0.7874 -0.4064)
			(stroke
				(width 0.1524)
				(type default)
			)
			(layer "F.SilkS")
		)
		(fp_line
			(start -0.7874 0.4064)
			(end -0.7874 -0.4064)
			(stroke
				(width 0.1524)
				(type default)
			)
			(layer "F.SilkS")
		)
		(fp_line
			(start 0.7874 -0.4064)
			(end 0.7874 0.4064)
			(stroke
				(width 0.1524)
				(type default)
			)
			(layer "F.SilkS")
		)
		(fp_line
			(start 0.7874 0.4064)
			(end -0.7874 0.4064)
			(stroke
				(width 0.1524)
				(type default)
			)
			(layer "F.SilkS")
		)
		(fp_line
			(start -0.67945 -0.305054)
			(end -0.12065 -0.305054)
			(stroke
				(width 0.1)
				(type default)
			)
			(layer "F.Fab")
		)
		(fp_line
			(start -0.67945 0.3048)
			(end -0.67945 -0.305054)
			(stroke
				(width 0.1)
				(type default)
			)
			(layer "F.Fab")
		)
		(fp_line
			(start -0.12065 -0.305054)
			(end -0.12065 -0.2794)
			(stroke
				(width 0.1)
				(type default)
			)
			(layer "F.Fab")
		)
		(fp_line
			(start -0.12065 -0.2794)
			(end 0.12065 -0.2794)
			(stroke
				(width 0.1)
				(type default)
			)
			(layer "F.Fab")
		)
		(fp_line
			(start -0.12065 0.2794)
			(end -0.12065 0.3048)
			(stroke
				(width 0.1)
				(type default)
			)
			(layer "F.Fab")
		)
		(fp_line
			(start -0.12065 0.3048)
			(end -0.67945 0.3048)
			(stroke
				(width 0.1)
				(type default)
			)
			(layer "F.Fab")
		)
		(fp_line
			(start 0.120396 0.2794)
			(end -0.12065 0.2794)
			(stroke
				(width 0.1)
				(type default)
			)
			(layer "F.Fab")
		)
		(fp_line
			(start 0.120396 0.3048)
			(end 0.120396 0.2794)
			(stroke
				(width 0.1)
				(type default)
			)
			(layer "F.Fab")
		)
		(fp_line
			(start 0.12065 -0.3048)
			(end 0.67945 -0.3048)
			(stroke
				(width 0.1)
				(type default)
			)
			(layer "F.Fab")
		)
		(fp_line
			(start 0.12065 -0.2794)
			(end 0.12065 -0.3048)
			(stroke
				(width 0.1)
				(type default)
			)
			(layer "F.Fab")
		)
		(fp_line
			(start 0.67945 -0.3048)
			(end 0.67945 0.3048)
			(stroke
				(width 0.1)
				(type default)
			)
			(layer "F.Fab")
		)
		(fp_line
			(start 0.67945 0.3048)
			(end 0.120396 0.3048)
			(stroke
				(width 0.1)
				(type default)
			)
			(layer "F.Fab")
		)
		(pad "1" smd circle
			(at -0.40005 0)
			(size 0 0)
			(layers "F.Cu" "F.Mask" "F.Paste")
			(net "SMB_INA230_3V3AUX_SCL")
		)
		(pad "2" smd circle
			(at 0.40005 0)
			(size 0 0)
			(layers "F.Cu" "F.Mask" "F.Paste")
			(net "SMB_INA230_7_3V3AUX_SCL_R")
		)
	)
	(footprint ""
		(layer "F.Cu")
		(at 329.592178 -41.160954 180)
		(property "Reference" "R2907"
			(at 0 0 180)
			(layer "F.SilkS")
			(hide yes)
			(effects
				(font
					(size 1.27 1.27)
				)
			)
		)
		(property "Value" ""
			(at 0 0 180)
			(layer "F.Fab")
			(effects
				(font
					(size 1.27 1.27)
				)
			)
		)
		(duplicate_pad_numbers_are_jumpers no)
		(fp_line
			(start 0.7874 0.4064)
			(end -0.7874 0.4064)
			(stroke
				(width 0.1524)
				(type default)
			)
			(layer "F.SilkS")
		)
		(fp_line
			(start 0.7874 -0.4064)
			(end 0.7874 0.4064)
			(stroke
				(width 0.1524)
				(type default)
			)
			(layer "F.SilkS")
		)
		(fp_line
			(start -0.7874 0.4064)
			(end -0.7874 -0.4064)
			(stroke
				(width 0.1524)
				(type default)
			)
			(layer "F.SilkS")
		)
		(fp_line
			(start -0.7874 -0.4064)
			(end 0.7874 -0.4064)
			(stroke
				(width 0.1524)
				(type default)
			)
			(layer "F.SilkS")
		)
		(fp_line
			(start 0.67945 0.3048)
			(end 0.120396 0.3048)
			(stroke
				(width 0.1)
				(type default)
			)
			(layer "F.Fab")
		)
		(fp_line
			(start 0.67945 -0.3048)
			(end 0.67945 0.3048)
			(stroke
				(width 0.1)
				(type default)
			)
			(layer "F.Fab")
		)
		(fp_line
			(start 0.12065 -0.2794)
			(end 0.12065 -0.3048)
			(stroke
				(width 0.1)
				(type default)
			)
			(layer "F.Fab")
		)
		(fp_line
			(start 0.12065 -0.3048)
			(end 0.67945 -0.3048)
			(stroke
				(width 0.1)
				(type default)
			)
			(layer "F.Fab")
		)
		(fp_line
			(start 0.120396 0.3048)
			(end 0.120396 0.2794)
			(stroke
				(width 0.1)
				(type default)
			)
			(layer "F.Fab")
		)
		(fp_line
			(start 0.120396 0.2794)
			(end -0.12065 0.2794)
			(stroke
				(width 0.1)
				(type default)
			)
			(layer "F.Fab")
		)
		(fp_line
			(start -0.12065 0.3048)
			(end -0.67945 0.3048)
			(stroke
				(width 0.1)
				(type default)
			)
			(layer "F.Fab")
		)
		(fp_line
			(start -0.12065 0.2794)
			(end -0.12065 0.3048)
			(stroke
				(width 0.1)
				(type default)
			)
			(layer "F.Fab")
		)
		(fp_line
			(start -0.12065 -0.2794)
			(end 0.12065 -0.2794)
			(stroke
				(width 0.1)
				(type default)
			)
			(layer "F.Fab")
		)
		(fp_line
			(start -0.12065 -0.305054)
			(end -0.12065 -0.2794)
			(stroke
				(width 0.1)
				(type default)
			)
			(layer "F.Fab")
		)
		(fp_line
			(start -0.67945 0.3048)
			(end -0.67945 -0.305054)
			(stroke
				(width 0.1)
				(type default)
			)
			(layer "F.Fab")
		)
		(fp_line
			(start -0.67945 -0.305054)
			(end -0.12065 -0.305054)
			(stroke
				(width 0.1)
				(type default)
			)
			(layer "F.Fab")
		)
		(pad "1" smd circle
			(at -0.40005 0 180)
			(size 0 0)
			(layers "F.Cu" "F.Mask" "F.Paste")
			(net "P3V3_AUX")
		)
		(pad "2" smd circle
			(at 0.40005 0 180)
			(size 0 0)
			(layers "F.Cu" "F.Mask" "F.Paste")
			(net "P3V3_AUX_ADC")
		)
	)
)
